(kicad_pcb
	(version 20260206)
	(generator "pcbnew")
	(generator_version "10.0")
	(general
		(thickness 1.6)
		(legacy_teardrops no)
	)
	(paper "A4")
	(title_block
		(title "01162023_DA0F0TEBIF0_F0T_Expander_BD_F_brd_V02_OCP.brd")
		(comment 1 "Grand Teton / footprints 5179-5184 of 9728")
	)
	(layers
		(0 "F.Cu" signal "TOP")
		(4 "In1.Cu" signal "GND")
		(6 "In2.Cu" signal "VCC")
		(8 "In3.Cu" signal "VCC1")
		(10 "In4.Cu" signal "GND1")
		(12 "In5.Cu" signal "IN1")
		(14 "In6.Cu" signal "GND2")
		(16 "In7.Cu" signal "IN2")
		(18 "In8.Cu" signal "GND3")
		(20 "In9.Cu" signal "IN3")
		(22 "In10.Cu" signal "GND4")
		(24 "In11.Cu" signal "IN4")
		(26 "In12.Cu" signal "GND5")
		(28 "In13.Cu" signal "IN5")
		(30 "In14.Cu" signal "GND6")
		(32 "In15.Cu" signal "IN6")
		(34 "In16.Cu" signal "GND7")
		(2 "B.Cu" signal "BOTTOM")
		(9 "F.Adhes" user "F.Adhesive")
		(11 "B.Adhes" user "B.Adhesive")
		(13 "F.Paste" user "Package Geometry/Pastemask Top")
		(15 "B.Paste" user "Package Geometry/Pastemask Bottom")
		(5 "F.SilkS" user "Ref Des/Silkscreen Top")
		(7 "B.SilkS" user "Ref Des/Silkscreen Bottom")
		(1 "F.Mask" user "Board Geometry/Soldermask Top")
		(3 "B.Mask" user "Board Geometry/Soldermask Bottom")
		(17 "Dwgs.User" user "User.Drawings")
		(19 "Cmts.User" user "User.Comments")
		(21 "Eco1.User" user "User.Eco1")
		(23 "Eco2.User" user "User.Eco2")
		(25 "Edge.Cuts" user "Board Geometry/Outline")
		(27 "Margin" user)
		(31 "F.CrtYd" user "Package Geometry/Place Bound Top")
		(29 "B.CrtYd" user "Package Geometry/Place Bound Bottom")
		(35 "F.Fab" user "Ref Des/Assembly Top")
		(33 "B.Fab" user "Ref Des/Assembly Bottom")
	)
	(footprint ""
		(layer "F.Cu")
		(at 397.967962 -19.453098)
		(property "Reference" "R1724"
			(at 0 0 0)
			(layer "F.SilkS")
			(hide yes)
			(effects
				(font
					(size 1.27 1.27)
				)
			)
		)
		(property "Value" ""
			(at 0 0 0)
			(layer "F.Fab")
			(effects
				(font
					(size 1.27 1.27)
				)
			)
		)
		(duplicate_pad_numbers_are_jumpers no)
		(fp_line
			(start -0.7874 -0.4064)
			(end 0.7874 -0.4064)
			(stroke
				(width 0.1524)
				(type default)
			)
			(layer "F.SilkS")
		)
		(fp_line
			(start -0.7874 0.4064)
			(end -0.7874 -0.4064)
			(stroke
				(width 0.1524)
				(type default)
			)
			(layer "F.SilkS")
		)
		(fp_line
			(start 0.7874 -0.4064)
			(end 0.7874 0.4064)
			(stroke
				(width 0.1524)
				(type default)
			)
			(layer "F.SilkS")
		)
		(fp_line
			(start 0.7874 0.4064)
			(end -0.7874 0.4064)
			(stroke
				(width 0.1524)
				(type default)
			)
			(layer "F.SilkS")
		)
		(fp_line
			(start -0.67945 -0.305054)
			(end -0.12065 -0.305054)
			(stroke
				(width 0.1)
				(type default)
			)
			(layer "F.Fab")
		)
		(fp_line
			(start -0.67945 0.3048)
			(end -0.67945 -0.305054)
			(stroke
				(width 0.1)
				(type default)
			)
			(layer "F.Fab")
		)
		(fp_line
			(start -0.12065 -0.305054)
			(end -0.12065 -0.2794)
			(stroke
				(width 0.1)
				(type default)
			)
			(layer "F.Fab")
		)
		(fp_line
			(start -0.12065 -0.2794)
			(end 0.12065 -0.2794)
			(stroke
				(width 0.1)
				(type default)
			)
			(layer "F.Fab")
		)
		(fp_line
			(start -0.12065 0.2794)
			(end -0.12065 0.3048)
			(stroke
				(width 0.1)
				(type default)
			)
			(layer "F.Fab")
		)
		(fp_line
			(start -0.12065 0.3048)
			(end -0.67945 0.3048)
			(stroke
				(width 0.1)
				(type default)
			)
			(layer "F.Fab")
		)
		(fp_line
			(start 0.120396 0.2794)
			(end -0.12065 0.2794)
			(stroke
				(width 0.1)
				(type default)
			)
			(layer "F.Fab")
		)
		(fp_line
			(start 0.120396 0.3048)
			(end 0.120396 0.2794)
			(stroke
				(width 0.1)
				(type default)
			)
			(layer "F.Fab")
		)
		(fp_line
			(start 0.12065 -0.3048)
			(end 0.67945 -0.3048)
			(stroke
				(width 0.1)
				(type default)
			)
			(layer "F.Fab")
		)
		(fp_line
			(start 0.12065 -0.2794)
			(end 0.12065 -0.3048)
			(stroke
				(width 0.1)
				(type default)
			)
			(layer "F.Fab")
		)
		(fp_line
			(start 0.67945 -0.3048)
			(end 0.67945 0.3048)
			(stroke
				(width 0.1)
				(type default)
			)
			(layer "F.Fab")
		)
		(fp_line
			(start 0.67945 0.3048)
			(end 0.120396 0.3048)
			(stroke
				(width 0.1)
				(type default)
			)
			(layer "F.Fab")
		)
		(pad "1" smd circle
			(at -0.40005 0)
			(size 0 0)
			(layers "F.Cu" "F.Mask" "F.Paste")
			(net "SMB_ISO_SSD13_R_SDA")
		)
		(pad "2" smd circle
			(at 0.40005 0)
			(size 0 0)
			(layers "F.Cu" "F.Mask" "F.Paste")
			(net "SMB_ISO_SSD13_SDA")
		)
	)
	(footprint ""
		(layer "F.Cu")
		(at 9.62914 -311.76087 180)
		(property "Reference" "PC208"
			(at 0 0 180)
			(layer "F.SilkS")
			(hide yes)
			(effects
				(font
					(size 1.27 1.27)
				)
			)
		)
		(property "Value" ""
			(at 0 0 180)
			(layer "F.Fab")
			(effects
				(font
					(size 1.27 1.27)
				)
			)
		)
		(duplicate_pad_numbers_are_jumpers no)
		(fp_line
			(start 1.524 0.762)
			(end -1.524 0.762)
			(stroke
				(width 0.1524)
				(type default)
			)
			(layer "F.SilkS")
		)
		(fp_line
			(start 1.524 -0.762)
			(end 1.524 0.762)
			(stroke
				(width 0.1524)
				(type default)
			)
			(layer "F.SilkS")
		)
		(fp_line
			(start -1.524 0.762)
			(end -1.524 -0.762)
			(stroke
				(width 0.1524)
				(type default)
			)
			(layer "F.SilkS")
		)
		(fp_line
			(start -1.524 -0.762)
			(end 1.524 -0.762)
			(stroke
				(width 0.1524)
				(type default)
			)
			(layer "F.SilkS")
		)
		(fp_line
			(start 1.1049 0.724916)
			(end 1.1049 -0.724916)
			(stroke
				(width 0.1)
				(type default)
			)
			(layer "F.Fab")
		)
		(fp_line
			(start 1.1049 -0.724916)
			(end -1.1049 -0.724916)
			(stroke
				(width 0.1)
				(type default)
			)
			(layer "F.Fab")
		)
		(fp_line
			(start -1.1049 0.724916)
			(end 1.1049 0.724916)
			(stroke
				(width 0.1)
				(type default)
			)
			(layer "F.Fab")
		)
		(fp_line
			(start -1.1049 -0.724916)
			(end -1.1049 0.724916)
			(stroke
				(width 0.1)
				(type default)
			)
			(layer "F.Fab")
		)
		(pad "1" smd rect
			(at -0.889 0)
			(size 1.016 1.27)
			(layers "F.Cu" "F.Mask" "F.Paste")
			(net "SW_P12V_P1V25_PEX0_FLT")
		)
		(pad "2" smd rect
			(at 0.889 0)
			(size 1.016 1.27)
			(layers "F.Cu" "F.Mask" "F.Paste")
			(net "GND")
		)
	)
	(footprint ""
		(layer "F.Cu")
		(at 119.225314 -117.313456)
		(property "Reference" "PC593"
			(at 0 0 0)
			(layer "F.SilkS")
			(hide yes)
			(effects
				(font
					(size 1.27 1.27)
				)
			)
		)
		(property "Value" ""
			(at 0 0 0)
			(layer "F.Fab")
			(effects
				(font
					(size 1.27 1.27)
				)
			)
		)
		(duplicate_pad_numbers_are_jumpers no)
		(fp_line
			(start -0.7874 -0.4064)
			(end 0.7874 -0.4064)
			(stroke
				(width 0.1524)
				(type default)
			)
			(layer "F.SilkS")
		)
		(fp_line
			(start -0.7874 0.4064)
			(end -0.7874 -0.4064)
			(stroke
				(width 0.1524)
				(type default)
			)
			(layer "F.SilkS")
		)
		(fp_line
			(start 0.7874 -0.4064)
			(end 0.7874 0.4064)
			(stroke
				(width 0.1524)
				(type default)
			)
			(layer "F.SilkS")
		)
		(fp_line
			(start 0.7874 0.4064)
			(end -0.7874 0.4064)
			(stroke
				(width 0.1524)
				(type default)
			)
			(layer "F.SilkS")
		)
		(fp_line
			(start -0.67945 -0.305054)
			(end -0.12065 -0.305054)
			(stroke
				(width 0.1)
				(type default)
			)
			(layer "F.Fab")
		)
		(fp_line
			(start -0.67945 0.3048)
			(end -0.67945 -0.305054)
			(stroke
				(width 0.1)
				(type default)
			)
			(layer "F.Fab")
		)
		(fp_line
			(start -0.12065 -0.305054)
			(end -0.12065 -0.2794)
			(stroke
				(width 0.1)
				(type default)
			)
			(layer "F.Fab")
		)
		(fp_line
			(start -0.12065 -0.2794)
			(end 0.12065 -0.2794)
			(stroke
				(width 0.1)
				(type default)
			)
			(layer "F.Fab")
		)
		(fp_line
			(start -0.12065 0.2794)
			(end -0.12065 0.3048)
			(stroke
				(width 0.1)
				(type default)
			)
			(layer "F.Fab")
		)
		(fp_line
			(start -0.12065 0.3048)
			(end -0.67945 0.3048)
			(stroke
				(width 0.1)
				(type default)
			)
			(layer "F.Fab")
		)
		(fp_line
			(start 0.120396 0.2794)
			(end -0.12065 0.2794)
			(stroke
				(width 0.1)
				(type default)
			)
			(layer "F.Fab")
		)
		(fp_line
			(start 0.120396 0.3048)
			(end 0.120396 0.2794)
			(stroke
				(width 0.1)
				(type default)
			)
			(layer "F.Fab")
		)
		(fp_line
			(start 0.12065 -0.3048)
			(end 0.67945 -0.3048)
			(stroke
				(width 0.1)
				(type default)
			)
			(layer "F.Fab")
		)
		(fp_line
			(start 0.12065 -0.2794)
			(end 0.12065 -0.3048)
			(stroke
				(width 0.1)
				(type default)
			)
			(layer "F.Fab")
		)
		(fp_line
			(start 0.67945 -0.3048)
			(end 0.67945 0.3048)
			(stroke
				(width 0.1)
				(type default)
			)
			(layer "F.Fab")
		)
		(fp_line
			(start 0.67945 0.3048)
			(end 0.120396 0.3048)
			(stroke
				(width 0.1)
				(type default)
			)
			(layer "F.Fab")
		)
		(pad "1" smd circle
			(at -0.40005 0)
			(size 0 0)
			(layers "F.Cu" "F.Mask" "F.Paste")
			(net "P3V3_AUX")
		)
		(pad "2" smd circle
			(at 0.40005 0)
			(size 0 0)
			(layers "F.Cu" "F.Mask" "F.Paste")
			(net "GND")
		)
	)
	(footprint ""
		(layer "F.Cu")
		(at 368.55527 -35.876738)
		(property "Reference" "R6105"
			(at 0 0 0)
			(layer "F.SilkS")
			(hide yes)
			(effects
				(font
					(size 1.27 1.27)
				)
			)
		)
		(property "Value" ""
			(at 0 0 0)
			(layer "F.Fab")
			(effects
				(font
					(size 1.27 1.27)
				)
			)
		)
		(duplicate_pad_numbers_are_jumpers no)
		(fp_line
			(start -0.7874 -0.4064)
			(end 0.7874 -0.4064)
			(stroke
				(width 0.1524)
				(type default)
			)
			(layer "F.SilkS")
		)
		(fp_line
			(start -0.7874 0.4064)
			(end -0.7874 -0.4064)
			(stroke
				(width 0.1524)
				(type default)
			)
			(layer "F.SilkS")
		)
		(fp_line
			(start 0.7874 -0.4064)
			(end 0.7874 0.4064)
			(stroke
				(width 0.1524)
				(type default)
			)
			(layer "F.SilkS")
		)
		(fp_line
			(start 0.7874 0.4064)
			(end -0.7874 0.4064)
			(stroke
				(width 0.1524)
				(type default)
			)
			(layer "F.SilkS")
		)
		(fp_line
			(start -0.67945 -0.305054)
			(end -0.12065 -0.305054)
			(stroke
				(width 0.1)
				(type default)
			)
			(layer "F.Fab")
		)
		(fp_line
			(start -0.67945 0.3048)
			(end -0.67945 -0.305054)
			(stroke
				(width 0.1)
				(type default)
			)
			(layer "F.Fab")
		)
		(fp_line
			(start -0.12065 -0.305054)
			(end -0.12065 -0.2794)
			(stroke
				(width 0.1)
				(type default)
			)
			(layer "F.Fab")
		)
		(fp_line
			(start -0.12065 -0.2794)
			(end 0.12065 -0.2794)
			(stroke
				(width 0.1)
				(type default)
			)
			(layer "F.Fab")
		)
		(fp_line
			(start -0.12065 0.2794)
			(end -0.12065 0.3048)
			(stroke
				(width 0.1)
				(type default)
			)
			(layer "F.Fab")
		)
		(fp_line
			(start -0.12065 0.3048)
			(end -0.67945 0.3048)
			(stroke
				(width 0.1)
				(type default)
			)
			(layer "F.Fab")
		)
		(fp_line
			(start 0.120396 0.2794)
			(end -0.12065 0.2794)
			(stroke
				(width 0.1)
				(type default)
			)
			(layer "F.Fab")
		)
		(fp_line
			(start 0.120396 0.3048)
			(end 0.120396 0.2794)
			(stroke
				(width 0.1)
				(type default)
			)
			(layer "F.Fab")
		)
		(fp_line
			(start 0.12065 -0.3048)
			(end 0.67945 -0.3048)
			(stroke
				(width 0.1)
				(type default)
			)
			(layer "F.Fab")
		)
		(fp_line
			(start 0.12065 -0.2794)
			(end 0.12065 -0.3048)
			(stroke
				(width 0.1)
				(type default)
			)
			(layer "F.Fab")
		)
		(fp_line
			(start 0.67945 -0.3048)
			(end 0.67945 0.3048)
			(stroke
				(width 0.1)
				(type default)
			)
			(layer "F.Fab")
		)
		(fp_line
			(start 0.67945 0.3048)
			(end 0.120396 0.3048)
			(stroke
				(width 0.1)
				(type default)
			)
			(layer "F.Fab")
		)
		(pad "1" smd circle
			(at -0.40005 0)
			(size 0 0)
			(layers "F.Cu" "F.Mask" "F.Paste")
			(net "P3V3_AUX")
		)
		(pad "2" smd circle
			(at 0.40005 0)
			(size 0 0)
			(layers "F.Cu" "F.Mask" "F.Paste")
			(net "PWRGD_P3V3_SSD13_D")
		)
	)
	(footprint ""
		(layer "F.Cu")
		(at 17.853914 -413.969708 90)
		(property "Reference" "R5594"
			(at 0 0 90)
			(layer "F.SilkS")
			(hide yes)
			(effects
				(font
					(size 1.27 1.27)
				)
			)
		)
		(property "Value" ""
			(at 0 0 90)
			(layer "F.Fab")
			(effects
				(font
					(size 1.27 1.27)
				)
			)
		)
		(duplicate_pad_numbers_are_jumpers no)
		(fp_line
			(start 0.7874 -0.4064)
			(end 0.7874 0.4064)
			(stroke
				(width 0.1524)
				(type default)
			)
			(layer "F.SilkS")
		)
		(fp_line
			(start -0.7874 -0.4064)
			(end 0.7874 -0.4064)
			(stroke
				(width 0.1524)
				(type default)
			)
			(layer "F.SilkS")
		)
		(fp_line
			(start 0.7874 0.4064)
			(end -0.7874 0.4064)
			(stroke
				(width 0.1524)
				(type default)
			)
			(layer "F.SilkS")
		)
		(fp_line
			(start -0.7874 0.4064)
			(end -0.7874 -0.4064)
			(stroke
				(width 0.1524)
				(type default)
			)
			(layer "F.SilkS")
		)
		(fp_line
			(start -0.12065 -0.305054)
			(end -0.12065 -0.2794)
			(stroke
				(width 0.1)
				(type default)
			)
			(layer "F.Fab")
		)
		(fp_line
			(start -0.67945 -0.305054)
			(end -0.12065 -0.305054)
			(stroke
				(width 0.1)
				(type default)
			)
			(layer "F.Fab")
		)
		(fp_line
			(start 0.67945 -0.3048)
			(end 0.67945 0.3048)
			(stroke
				(width 0.1)
				(type default)
			)
			(layer "F.Fab")
		)
		(fp_line
			(start 0.12065 -0.3048)
			(end 0.67945 -0.3048)
			(stroke
				(width 0.1)
				(type default)
			)
			(layer "F.Fab")
		)
		(fp_line
			(start 0.12065 -0.2794)
			(end 0.12065 -0.3048)
			(stroke
				(width 0.1)
				(type default)
			)
			(layer "F.Fab")
		)
		(fp_line
			(start -0.12065 -0.2794)
			(end 0.12065 -0.2794)
			(stroke
				(width 0.1)
				(type default)
			)
			(layer "F.Fab")
		)
		(fp_line
			(start 0.120396 0.2794)
			(end -0.12065 0.2794)
			(stroke
				(width 0.1)
				(type default)
			)
			(layer "F.Fab")
		)
		(fp_line
			(start -0.12065 0.2794)
			(end -0.12065 0.3048)
			(stroke
				(width 0.1)
				(type default)
			)
			(layer "F.Fab")
		)
		(fp_line
			(start 0.67945 0.3048)
			(end 0.120396 0.3048)
			(stroke
				(width 0.1)
				(type default)
			)
			(layer "F.Fab")
		)
		(fp_line
			(start 0.120396 0.3048)
			(end 0.120396 0.2794)
			(stroke
				(width 0.1)
				(type default)
			)
			(layer "F.Fab")
		)
		(fp_line
			(start -0.12065 0.3048)
			(end -0.67945 0.3048)
			(stroke
				(width 0.1)
				(type default)
			)
			(layer "F.Fab")
		)
		(fp_line
			(start -0.67945 0.3048)
			(end -0.67945 -0.305054)
			(stroke
				(width 0.1)
				(type default)
			)
			(layer "F.Fab")
		)
		(pad "1" smd circle
			(at -0.40005 0 90)
			(size 0 0)
			(layers "F.Cu" "F.Mask" "F.Paste")
			(net "LM75_0_A0")
		)
		(pad "2" smd circle
			(at 0.40005 0 90)
			(size 0 0)
			(layers "F.Cu" "F.Mask" "F.Paste")
			(net "P3V3_AUX")
		)
	)
	(footprint ""
		(layer "F.Cu")
		(at 452.759318 -22.955504 90)
		(property "Reference" "R1742"
			(at 0 0 90)
			(layer "F.SilkS")
			(hide yes)
			(effects
				(font
					(size 1.27 1.27)
				)
			)
		)
		(property "Value" ""
			(at 0 0 90)
			(layer "F.Fab")
			(effects
				(font
					(size 1.27 1.27)
				)
			)
		)
		(duplicate_pad_numbers_are_jumpers no)
		(fp_line
			(start 0.7874 -0.4064)
			(end 0.7874 0.4064)
			(stroke
				(width 0.1524)
				(type default)
			)
			(layer "F.SilkS")
		)
		(fp_line
			(start -0.7874 -0.4064)
			(end 0.7874 -0.4064)
			(stroke
				(width 0.1524)
				(type default)
			)
			(layer "F.SilkS")
		)
		(fp_line
			(start 0.7874 0.4064)
			(end -0.7874 0.4064)
			(stroke
				(width 0.1524)
				(type default)
			)
			(layer "F.SilkS")
		)
		(fp_line
			(start -0.7874 0.4064)
			(end -0.7874 -0.4064)
			(stroke
				(width 0.1524)
				(type default)
			)
			(layer "F.SilkS")
		)
		(fp_line
			(start -0.12065 -0.305054)
			(end -0.12065 -0.2794)
			(stroke
				(width 0.1)
				(type default)
			)
			(layer "F.Fab")
		)
		(fp_line
			(start -0.67945 -0.305054)
			(end -0.12065 -0.305054)
			(stroke
				(width 0.1)
				(type default)
			)
			(layer "F.Fab")
		)
		(fp_line
			(start 0.67945 -0.3048)
			(end 0.67945 0.3048)
			(stroke
				(width 0.1)
				(type default)
			)
			(layer "F.Fab")
		)
		(fp_line
			(start 0.12065 -0.3048)
			(end 0.67945 -0.3048)
			(stroke
				(width 0.1)
				(type default)
			)
			(layer "F.Fab")
		)
		(fp_line
			(start 0.12065 -0.2794)
			(end 0.12065 -0.3048)
			(stroke
				(width 0.1)
				(type default)
			)
			(layer "F.Fab")
		)
		(fp_line
			(start -0.12065 -0.2794)
			(end 0.12065 -0.2794)
			(stroke
				(width 0.1)
				(type default)
			)
			(layer "F.Fab")
		)
		(fp_line
			(start 0.120396 0.2794)
			(end -0.12065 0.2794)
			(stroke
				(width 0.1)
				(type default)
			)
			(layer "F.Fab")
		)
		(fp_line
			(start -0.12065 0.2794)
			(end -0.12065 0.3048)
			(stroke
				(width 0.1)
				(type default)
			)
			(layer "F.Fab")
		)
		(fp_line
			(start 0.67945 0.3048)
			(end 0.120396 0.3048)
			(stroke
				(width 0.1)
				(type default)
			)
			(layer "F.Fab")
		)
		(fp_line
			(start 0.120396 0.3048)
			(end 0.120396 0.2794)
			(stroke
				(width 0.1)
				(type default)
			)
			(layer "F.Fab")
		)
		(fp_line
			(start -0.12065 0.3048)
			(end -0.67945 0.3048)
			(stroke
				(width 0.1)
				(type default)
			)
			(layer "F.Fab")
		)
		(fp_line
			(start -0.67945 0.3048)
			(end -0.67945 -0.305054)
			(stroke
				(width 0.1)
				(type default)
			)
			(layer "F.Fab")
		)
		(pad "1" smd circle
			(at -0.40005 0 90)
			(size 0 0)
			(layers "F.Cu" "F.Mask" "F.Paste")
			(net "SMB_BIC_I2C9_MUX1_SSD15_R_SCL")
		)
		(pad "2" smd circle
			(at 0.40005 0 90)
			(size 0 0)
			(layers "F.Cu" "F.Mask" "F.Paste")
			(net "SMB_ISO_SSD15_SCL")
		)
	)
)
